(kicad_pcb
	(version 20260206)
	(generator "pcbnew")
	(generator_version "10.0")
	(general
		(thickness 1.6)
		(legacy_teardrops no)
	)
	(paper "A4")
	(title_block
		(title "01162023_DA0F0TEBIF0_F0T_Expander_BD_F_brd_V02_OCP.brd")
		(comment 1 "Grand Teton / footprints 1087-1093 of 9728")
	)
	(layers
		(0 "F.Cu" signal "TOP")
		(4 "In1.Cu" signal "GND")
		(6 "In2.Cu" signal "VCC")
		(8 "In3.Cu" signal "VCC1")
		(10 "In4.Cu" signal "GND1")
		(12 "In5.Cu" signal "IN1")
		(14 "In6.Cu" signal "GND2")
		(16 "In7.Cu" signal "IN2")
		(18 "In8.Cu" signal "GND3")
		(20 "In9.Cu" signal "IN3")
		(22 "In10.Cu" signal "GND4")
		(24 "In11.Cu" signal "IN4")
		(26 "In12.Cu" signal "GND5")
		(28 "In13.Cu" signal "IN5")
		(30 "In14.Cu" signal "GND6")
		(32 "In15.Cu" signal "IN6")
		(34 "In16.Cu" signal "GND7")
		(2 "B.Cu" signal "BOTTOM")
		(9 "F.Adhes" user "F.Adhesive")
		(11 "B.Adhes" user "B.Adhesive")
		(13 "F.Paste" user "Package Geometry/Pastemask Top")
		(15 "B.Paste" user "Package Geometry/Pastemask Bottom")
		(5 "F.SilkS" user "Ref Des/Silkscreen Top")
		(7 "B.SilkS" user "Ref Des/Silkscreen Bottom")
		(1 "F.Mask" user "Board Geometry/Soldermask Top")
		(3 "B.Mask" user "Board Geometry/Soldermask Bottom")
		(17 "Dwgs.User" user "User.Drawings")
		(19 "Cmts.User" user "User.Comments")
		(21 "Eco1.User" user "User.Eco1")
		(23 "Eco2.User" user "User.Eco2")
		(25 "Edge.Cuts" user "Board Geometry/Outline")
		(27 "Margin" user)
		(31 "F.CrtYd" user "Package Geometry/Place Bound Top")
		(29 "B.CrtYd" user "Package Geometry/Place Bound Bottom")
		(35 "F.Fab" user "Ref Des/Assembly Top")
		(33 "B.Fab" user "Ref Des/Assembly Bottom")
	)
	(footprint ""
		(layer "F.Cu")
		(at 445.954658 -22.867366 90)
		(property "Reference" "C3983"
			(at 0 0 90)
			(layer "F.SilkS")
			(hide yes)
			(effects
				(font
					(size 1.27 1.27)
				)
			)
		)
		(property "Value" ""
			(at 0 0 90)
			(layer "F.Fab")
			(effects
				(font
					(size 1.27 1.27)
				)
			)
		)
		(duplicate_pad_numbers_are_jumpers no)
		(fp_line
			(start 0.7874 -0.4064)
			(end 0.7874 0.4064)
			(stroke
				(width 0.1524)
				(type default)
			)
			(layer "F.SilkS")
		)
		(fp_line
			(start -0.7874 -0.4064)
			(end 0.7874 -0.4064)
			(stroke
				(width 0.1524)
				(type default)
			)
			(layer "F.SilkS")
		)
		(fp_line
			(start 0.7874 0.4064)
			(end -0.7874 0.4064)
			(stroke
				(width 0.1524)
				(type default)
			)
			(layer "F.SilkS")
		)
		(fp_line
			(start -0.7874 0.4064)
			(end -0.7874 -0.4064)
			(stroke
				(width 0.1524)
				(type default)
			)
			(layer "F.SilkS")
		)
		(fp_line
			(start -0.12065 -0.305054)
			(end -0.12065 -0.2794)
			(stroke
				(width 0.1)
				(type default)
			)
			(layer "F.Fab")
		)
		(fp_line
			(start -0.67945 -0.305054)
			(end -0.12065 -0.305054)
			(stroke
				(width 0.1)
				(type default)
			)
			(layer "F.Fab")
		)
		(fp_line
			(start 0.67945 -0.3048)
			(end 0.67945 0.3048)
			(stroke
				(width 0.1)
				(type default)
			)
			(layer "F.Fab")
		)
		(fp_line
			(start 0.12065 -0.3048)
			(end 0.67945 -0.3048)
			(stroke
				(width 0.1)
				(type default)
			)
			(layer "F.Fab")
		)
		(fp_line
			(start 0.12065 -0.2794)
			(end 0.12065 -0.3048)
			(stroke
				(width 0.1)
				(type default)
			)
			(layer "F.Fab")
		)
		(fp_line
			(start -0.12065 -0.2794)
			(end 0.12065 -0.2794)
			(stroke
				(width 0.1)
				(type default)
			)
			(layer "F.Fab")
		)
		(fp_line
			(start 0.120396 0.2794)
			(end -0.12065 0.2794)
			(stroke
				(width 0.1)
				(type default)
			)
			(layer "F.Fab")
		)
		(fp_line
			(start -0.12065 0.2794)
			(end -0.12065 0.3048)
			(stroke
				(width 0.1)
				(type default)
			)
			(layer "F.Fab")
		)
		(fp_line
			(start 0.67945 0.3048)
			(end 0.120396 0.3048)
			(stroke
				(width 0.1)
				(type default)
			)
			(layer "F.Fab")
		)
		(fp_line
			(start 0.120396 0.3048)
			(end 0.120396 0.2794)
			(stroke
				(width 0.1)
				(type default)
			)
			(layer "F.Fab")
		)
		(fp_line
			(start -0.12065 0.3048)
			(end -0.67945 0.3048)
			(stroke
				(width 0.1)
				(type default)
			)
			(layer "F.Fab")
		)
		(fp_line
			(start -0.67945 0.3048)
			(end -0.67945 -0.305054)
			(stroke
				(width 0.1)
				(type default)
			)
			(layer "F.Fab")
		)
		(pad "1" smd circle
			(at -0.40005 0 90)
			(size 0 0)
			(layers "F.Cu" "F.Mask" "F.Paste")
			(net "P12V_SSD15")
		)
		(pad "2" smd circle
			(at 0.40005 0 90)
			(size 0 0)
			(layers "F.Cu" "F.Mask" "F.Paste")
			(net "GND")
		)
	)
	(footprint ""
		(layer "F.Cu")
		(at 387.580632 -110.088934)
		(property "Reference" "C684"
			(at 0 0 0)
			(layer "F.SilkS")
			(hide yes)
			(effects
				(font
					(size 1.27 1.27)
				)
			)
		)
		(property "Value" ""
			(at 0 0 0)
			(layer "F.Fab")
			(effects
				(font
					(size 1.27 1.27)
				)
			)
		)
		(duplicate_pad_numbers_are_jumpers no)
		(fp_line
			(start -0.299974 -0.150114)
			(end 0.299974 -0.150114)
			(stroke
				(width 0.1)
				(type default)
			)
			(layer "F.Fab")
		)
		(fp_line
			(start -0.299974 0.150114)
			(end -0.299974 -0.150114)
			(stroke
				(width 0.1)
				(type default)
			)
			(layer "F.Fab")
		)
		(fp_line
			(start 0.299974 -0.150114)
			(end 0.299974 0.150114)
			(stroke
				(width 0.1)
				(type default)
			)
			(layer "F.Fab")
		)
		(fp_line
			(start 0.299974 0.150114)
			(end -0.299974 0.150114)
			(stroke
				(width 0.1)
				(type default)
			)
			(layer "F.Fab")
		)
		(pad "1" smd rect
			(at -0.2667 0)
			(size 0.3048 0.381)
			(layers "F.Cu" "F.Mask" "F.Paste")
			(net "P5E_PEX3_STN1_TX_DP<22>")
		)
		(pad "2" smd rect
			(at 0.2667 0)
			(size 0.3048 0.381)
			(layers "F.Cu" "F.Mask" "F.Paste")
			(net "P5E_PEX3_STN1_TX_C_DP<22>")
		)
	)
	(footprint ""
		(layer "F.Cu")
		(at 142.305024 -197.529196 -90)
		(property "Reference" "R5775"
			(at 0 0 270)
			(layer "F.SilkS")
			(hide yes)
			(effects
				(font
					(size 1.27 1.27)
				)
			)
		)
		(property "Value" ""
			(at 0 0 270)
			(layer "F.Fab")
			(effects
				(font
					(size 1.27 1.27)
				)
			)
		)
		(duplicate_pad_numbers_are_jumpers no)
		(fp_line
			(start -0.7874 0.4064)
			(end -0.7874 -0.4064)
			(stroke
				(width 0.1524)
				(type default)
			)
			(layer "F.SilkS")
		)
		(fp_line
			(start 0.7874 0.4064)
			(end -0.7874 0.4064)
			(stroke
				(width 0.1524)
				(type default)
			)
			(layer "F.SilkS")
		)
		(fp_line
			(start -0.7874 -0.4064)
			(end 0.7874 -0.4064)
			(stroke
				(width 0.1524)
				(type default)
			)
			(layer "F.SilkS")
		)
		(fp_line
			(start 0.7874 -0.4064)
			(end 0.7874 0.4064)
			(stroke
				(width 0.1524)
				(type default)
			)
			(layer "F.SilkS")
		)
		(fp_line
			(start -0.67945 0.3048)
			(end -0.67945 -0.305054)
			(stroke
				(width 0.1)
				(type default)
			)
			(layer "F.Fab")
		)
		(fp_line
			(start -0.12065 0.3048)
			(end -0.67945 0.3048)
			(stroke
				(width 0.1)
				(type default)
			)
			(layer "F.Fab")
		)
		(fp_line
			(start 0.120396 0.3048)
			(end 0.120396 0.2794)
			(stroke
				(width 0.1)
				(type default)
			)
			(layer "F.Fab")
		)
		(fp_line
			(start 0.67945 0.3048)
			(end 0.120396 0.3048)
			(stroke
				(width 0.1)
				(type default)
			)
			(layer "F.Fab")
		)
		(fp_line
			(start -0.12065 0.2794)
			(end -0.12065 0.3048)
			(stroke
				(width 0.1)
				(type default)
			)
			(layer "F.Fab")
		)
		(fp_line
			(start 0.120396 0.2794)
			(end -0.12065 0.2794)
			(stroke
				(width 0.1)
				(type default)
			)
			(layer "F.Fab")
		)
		(fp_line
			(start -0.12065 -0.2794)
			(end 0.12065 -0.2794)
			(stroke
				(width 0.1)
				(type default)
			)
			(layer "F.Fab")
		)
		(fp_line
			(start 0.12065 -0.2794)
			(end 0.12065 -0.3048)
			(stroke
				(width 0.1)
				(type default)
			)
			(layer "F.Fab")
		)
		(fp_line
			(start 0.12065 -0.3048)
			(end 0.67945 -0.3048)
			(stroke
				(width 0.1)
				(type default)
			)
			(layer "F.Fab")
		)
		(fp_line
			(start 0.67945 -0.3048)
			(end 0.67945 0.3048)
			(stroke
				(width 0.1)
				(type default)
			)
			(layer "F.Fab")
		)
		(fp_line
			(start -0.67945 -0.305054)
			(end -0.12065 -0.305054)
			(stroke
				(width 0.1)
				(type default)
			)
			(layer "F.Fab")
		)
		(fp_line
			(start -0.12065 -0.305054)
			(end -0.12065 -0.2794)
			(stroke
				(width 0.1)
				(type default)
			)
			(layer "F.Fab")
		)
		(pad "1" smd circle
			(at -0.40005 0 270)
			(size 0 0)
			(layers "F.Cu" "F.Mask" "F.Paste")
			(net "RST_FT4232_CLI_R_N")
		)
		(pad "2" smd circle
			(at 0.40005 0 270)
			(size 0 0)
			(layers "F.Cu" "F.Mask" "F.Paste")
			(net "RST_FT4232_R_N")
		)
	)
	(footprint ""
		(layer "F.Cu")
		(at 235.623608 -146.704812)
		(property "Reference" "R4222"
			(at 0 0 0)
			(layer "F.SilkS")
			(hide yes)
			(effects
				(font
					(size 1.27 1.27)
				)
			)
		)
		(property "Value" ""
			(at 0 0 0)
			(layer "F.Fab")
			(effects
				(font
					(size 1.27 1.27)
				)
			)
		)
		(duplicate_pad_numbers_are_jumpers no)
		(fp_line
			(start -0.7874 -0.4064)
			(end 0.7874 -0.4064)
			(stroke
				(width 0.1524)
				(type default)
			)
			(layer "F.SilkS")
		)
		(fp_line
			(start -0.7874 0.4064)
			(end -0.7874 -0.4064)
			(stroke
				(width 0.1524)
				(type default)
			)
			(layer "F.SilkS")
		)
		(fp_line
			(start 0.7874 -0.4064)
			(end 0.7874 0.4064)
			(stroke
				(width 0.1524)
				(type default)
			)
			(layer "F.SilkS")
		)
		(fp_line
			(start 0.7874 0.4064)
			(end -0.7874 0.4064)
			(stroke
				(width 0.1524)
				(type default)
			)
			(layer "F.SilkS")
		)
		(fp_line
			(start -0.67945 -0.305054)
			(end -0.12065 -0.305054)
			(stroke
				(width 0.1)
				(type default)
			)
			(layer "F.Fab")
		)
		(fp_line
			(start -0.67945 0.3048)
			(end -0.67945 -0.305054)
			(stroke
				(width 0.1)
				(type default)
			)
			(layer "F.Fab")
		)
		(fp_line
			(start -0.12065 -0.305054)
			(end -0.12065 -0.2794)
			(stroke
				(width 0.1)
				(type default)
			)
			(layer "F.Fab")
		)
		(fp_line
			(start -0.12065 -0.2794)
			(end 0.12065 -0.2794)
			(stroke
				(width 0.1)
				(type default)
			)
			(layer "F.Fab")
		)
		(fp_line
			(start -0.12065 0.2794)
			(end -0.12065 0.3048)
			(stroke
				(width 0.1)
				(type default)
			)
			(layer "F.Fab")
		)
		(fp_line
			(start -0.12065 0.3048)
			(end -0.67945 0.3048)
			(stroke
				(width 0.1)
				(type default)
			)
			(layer "F.Fab")
		)
		(fp_line
			(start 0.120396 0.2794)
			(end -0.12065 0.2794)
			(stroke
				(width 0.1)
				(type default)
			)
			(layer "F.Fab")
		)
		(fp_line
			(start 0.120396 0.3048)
			(end 0.120396 0.2794)
			(stroke
				(width 0.1)
				(type default)
			)
			(layer "F.Fab")
		)
		(fp_line
			(start 0.12065 -0.3048)
			(end 0.67945 -0.3048)
			(stroke
				(width 0.1)
				(type default)
			)
			(layer "F.Fab")
		)
		(fp_line
			(start 0.12065 -0.2794)
			(end 0.12065 -0.3048)
			(stroke
				(width 0.1)
				(type default)
			)
			(layer "F.Fab")
		)
		(fp_line
			(start 0.67945 -0.3048)
			(end 0.67945 0.3048)
			(stroke
				(width 0.1)
				(type default)
			)
			(layer "F.Fab")
		)
		(fp_line
			(start 0.67945 0.3048)
			(end 0.120396 0.3048)
			(stroke
				(width 0.1)
				(type default)
			)
			(layer "F.Fab")
		)
		(pad "1" smd circle
			(at -0.40005 0)
			(size 0 0)
			(layers "F.Cu" "F.Mask" "F.Paste")
			(net "CLK_GEN_CK440_PEX_OE5_N")
		)
		(pad "2" smd circle
			(at 0.40005 0)
			(size 0 0)
			(layers "F.Cu" "F.Mask" "F.Paste")
			(net "P3V3")
		)
	)
	(footprint ""
		(layer "F.Cu")
		(at 438.71134 -107.29976)
		(property "Reference" "R758"
			(at 0 0 0)
			(layer "F.SilkS")
			(hide yes)
			(effects
				(font
					(size 1.27 1.27)
				)
			)
		)
		(property "Value" ""
			(at 0 0 0)
			(layer "F.Fab")
			(effects
				(font
					(size 1.27 1.27)
				)
			)
		)
		(duplicate_pad_numbers_are_jumpers no)
		(fp_line
			(start -3.937508 -1.8796)
			(end -3.937508 1.8796)
			(stroke
				(width 0.1524)
				(type default)
			)
			(layer "F.SilkS")
		)
		(fp_line
			(start -3.937508 1.8796)
			(end 3.937508 1.8796)
			(stroke
				(width 0.1524)
				(type default)
			)
			(layer "F.SilkS")
		)
		(fp_line
			(start 3.937508 -1.8796)
			(end -3.937508 -1.8796)
			(stroke
				(width 0.1524)
				(type default)
			)
			(layer "F.SilkS")
		)
		(fp_line
			(start 3.937508 1.8796)
			(end 3.937508 -1.8796)
			(stroke
				(width 0.1524)
				(type default)
			)
			(layer "F.SilkS")
		)
		(fp_line
			(start -3.275076 -1.674876)
			(end -3.275076 1.674876)
			(stroke
				(width 0.1)
				(type default)
			)
			(layer "F.Fab")
		)
		(fp_line
			(start -3.275076 1.674876)
			(end 3.275076 1.674876)
			(stroke
				(width 0.1)
				(type default)
			)
			(layer "F.Fab")
		)
		(fp_line
			(start 3.275076 -1.674876)
			(end -3.275076 -1.674876)
			(stroke
				(width 0.1)
				(type default)
			)
			(layer "F.Fab")
		)
		(fp_line
			(start 3.275076 1.674876)
			(end 3.275076 -1.674876)
			(stroke
				(width 0.1)
				(type default)
			)
			(layer "F.Fab")
		)
		(pad "1" smd rect
			(at -2.350008 0)
			(size 2.921 3.5052)
			(layers "F.Cu" "F.Mask" "F.Paste")
			(net "P12V_NIC7")
		)
		(pad "2" smd rect
			(at 2.350008 0)
			(size 2.921 3.5052)
			(layers "F.Cu" "F.Mask" "F.Paste")
			(net "P12V_NIC7_R")
		)
	)
	(footprint ""
		(layer "F.Cu")
		(at 28.406344 -252.356874 -90)
		(property "Reference" "R1188"
			(at 0 0 270)
			(layer "F.SilkS")
			(hide yes)
			(effects
				(font
					(size 1.27 1.27)
				)
			)
		)
		(property "Value" ""
			(at 0 0 270)
			(layer "F.Fab")
			(effects
				(font
					(size 1.27 1.27)
				)
			)
		)
		(duplicate_pad_numbers_are_jumpers no)
		(fp_line
			(start -0.7874 0.4064)
			(end -0.7874 -0.4064)
			(stroke
				(width 0.1524)
				(type default)
			)
			(layer "F.SilkS")
		)
		(fp_line
			(start 0.7874 0.4064)
			(end -0.7874 0.4064)
			(stroke
				(width 0.1524)
				(type default)
			)
			(layer "F.SilkS")
		)
		(fp_line
			(start -0.7874 -0.4064)
			(end 0.7874 -0.4064)
			(stroke
				(width 0.1524)
				(type default)
			)
			(layer "F.SilkS")
		)
		(fp_line
			(start 0.7874 -0.4064)
			(end 0.7874 0.4064)
			(stroke
				(width 0.1524)
				(type default)
			)
			(layer "F.SilkS")
		)
		(fp_line
			(start -0.67945 0.3048)
			(end -0.67945 -0.305054)
			(stroke
				(width 0.1)
				(type default)
			)
			(layer "F.Fab")
		)
		(fp_line
			(start -0.12065 0.3048)
			(end -0.67945 0.3048)
			(stroke
				(width 0.1)
				(type default)
			)
			(layer "F.Fab")
		)
		(fp_line
			(start 0.120396 0.3048)
			(end 0.120396 0.2794)
			(stroke
				(width 0.1)
				(type default)
			)
			(layer "F.Fab")
		)
		(fp_line
			(start 0.67945 0.3048)
			(end 0.120396 0.3048)
			(stroke
				(width 0.1)
				(type default)
			)
			(layer "F.Fab")
		)
		(fp_line
			(start -0.12065 0.2794)
			(end -0.12065 0.3048)
			(stroke
				(width 0.1)
				(type default)
			)
			(layer "F.Fab")
		)
		(fp_line
			(start 0.120396 0.2794)
			(end -0.12065 0.2794)
			(stroke
				(width 0.1)
				(type default)
			)
			(layer "F.Fab")
		)
		(fp_line
			(start -0.12065 -0.2794)
			(end 0.12065 -0.2794)
			(stroke
				(width 0.1)
				(type default)
			)
			(layer "F.Fab")
		)
		(fp_line
			(start 0.12065 -0.2794)
			(end 0.12065 -0.3048)
			(stroke
				(width 0.1)
				(type default)
			)
			(layer "F.Fab")
		)
		(fp_line
			(start 0.12065 -0.3048)
			(end 0.67945 -0.3048)
			(stroke
				(width 0.1)
				(type default)
			)
			(layer "F.Fab")
		)
		(fp_line
			(start 0.67945 -0.3048)
			(end 0.67945 0.3048)
			(stroke
				(width 0.1)
				(type default)
			)
			(layer "F.Fab")
		)
		(fp_line
			(start -0.67945 -0.305054)
			(end -0.12065 -0.305054)
			(stroke
				(width 0.1)
				(type default)
			)
			(layer "F.Fab")
		)
		(fp_line
			(start -0.12065 -0.305054)
			(end -0.12065 -0.2794)
			(stroke
				(width 0.1)
				(type default)
			)
			(layer "F.Fab")
		)
		(pad "1" smd circle
			(at -0.40005 0 270)
			(size 0 0)
			(layers "F.Cu" "F.Mask" "F.Paste")
			(net "GND")
		)
		(pad "2" smd circle
			(at 0.40005 0 270)
			(size 0 0)
			(layers "F.Cu" "F.Mask" "F.Paste")
			(net "PEX0_DBG_MODE3")
		)
	)
	(footprint ""
		(layer "F.Cu")
		(at 227.31476 -314.424314)
		(property "Reference" "PC225"
			(at 0 0 0)
			(layer "F.SilkS")
			(hide yes)
			(effects
				(font
					(size 1.27 1.27)
				)
			)
		)
		(property "Value" ""
			(at 0 0 0)
			(layer "F.Fab")
			(effects
				(font
					(size 1.27 1.27)
				)
			)
		)
		(duplicate_pad_numbers_are_jumpers no)
		(fp_line
			(start -1.524 -0.762)
			(end 1.524 -0.762)
			(stroke
				(width 0.1524)
				(type default)
			)
			(layer "F.SilkS")
		)
		(fp_line
			(start -1.524 0.762)
			(end -1.524 -0.762)
			(stroke
				(width 0.1524)
				(type default)
			)
			(layer "F.SilkS")
		)
		(fp_line
			(start 1.524 -0.762)
			(end 1.524 0.762)
			(stroke
				(width 0.1524)
				(type default)
			)
			(layer "F.SilkS")
		)
		(fp_line
			(start 1.524 0.762)
			(end -1.524 0.762)
			(stroke
				(width 0.1524)
				(type default)
			)
			(layer "F.SilkS")
		)
		(fp_line
			(start -1.1049 -0.724916)
			(end -1.1049 0.724916)
			(stroke
				(width 0.1)
				(type default)
			)
			(layer "F.Fab")
		)
		(fp_line
			(start -1.1049 0.724916)
			(end 1.1049 0.724916)
			(stroke
				(width 0.1)
				(type default)
			)
			(layer "F.Fab")
		)
		(fp_line
			(start 1.1049 -0.724916)
			(end -1.1049 -0.724916)
			(stroke
				(width 0.1)
				(type default)
			)
			(layer "F.Fab")
		)
		(fp_line
			(start 1.1049 0.724916)
			(end 1.1049 -0.724916)
			(stroke
				(width 0.1)
				(type default)
			)
			(layer "F.Fab")
		)
		(pad "1" smd rect
			(at -0.889 0 180)
			(size 1.016 1.27)
			(layers "F.Cu" "F.Mask" "F.Paste")
			(net "SW_P12V_P1V25_PEX1_FLT")
		)
		(pad "2" smd rect
			(at 0.889 0 180)
			(size 1.016 1.27)
			(layers "F.Cu" "F.Mask" "F.Paste")
			(net "GND")
		)
	)
)
